(kicad_pcb
	(version 20260206)
	(generator "pcbnew")
	(generator_version "10.0")
	(general
		(thickness 1.6)
		(legacy_teardrops no)
	)
	(paper "A4")
	(title_block
		(title "Bryce Canyon_SCC_16316-1_OCP.brd")
		(comment 1 "Bryce Canyon / footprints 880-887 of 1561")
	)
	(layers
		(0 "F.Cu" signal "TOP")
		(4 "In1.Cu" signal "L2GND")
		(6 "In2.Cu" signal "L3")
		(8 "In3.Cu" signal "L4VCC")
		(10 "In4.Cu" signal "L5VCC")
		(12 "In5.Cu" signal "L6")
		(14 "In6.Cu" signal "L7GND")
		(2 "B.Cu" signal "BOTTOM")
		(9 "F.Adhes" user "F.Adhesive")
		(11 "B.Adhes" user "B.Adhesive")
		(13 "F.Paste" user "Package Geometry/Pastemask Top")
		(15 "B.Paste" user "Package Geometry/Pastemask Bottom")
		(5 "F.SilkS" user "Ref Des/Silkscreen Top")
		(7 "B.SilkS" user "Ref Des/Silkscreen Bottom")
		(1 "F.Mask" user "Board Geometry/Soldermask Top")
		(3 "B.Mask" user "Board Geometry/Soldermask Bottom")
		(17 "Dwgs.User" user "User.Drawings")
		(19 "Cmts.User" user "User.Comments")
		(21 "Eco1.User" user "User.Eco1")
		(23 "Eco2.User" user "User.Eco2")
		(25 "Edge.Cuts" user "Board Geometry/Outline")
		(27 "Margin" user)
		(31 "F.CrtYd" user "Package Geometry/Place Bound Top")
		(29 "B.CrtYd" user "Package Geometry/Place Bound Bottom")
		(35 "F.Fab" user "Ref Des/Assembly Top")
		(33 "B.Fab" user "Ref Des/Assembly Bottom")
	)
	(footprint ""
		(layer "B.Cu")
		(at 125.5014 -73.8378 180)
		(property "Reference" "C274"
			(at 0 0 0)
			(layer "B.SilkS")
			(hide yes)
			(effects
				(font
					(size 1.27 1.27)
				)
				(justify mirror)
			)
		)
		(property "Value" "SC1U6D3V1MX-GP"
			(at -1.9177 2.0193 180)
			(unlocked yes)
			(layer "B.Fab")
			(hide yes)
			(effects
				(font
					(size 1.016 1.016)
					(thickness 0.1524)
				)
				(justify mirror)
			)
		)
		(property "Device Type" "C0201H14"
			(at -1.9177 0.4953 180)
			(unlocked yes)
			(layer "B.Fab")
			(hide yes)
			(effects
				(font
					(size 1.016 1.016)
					(thickness 0.1524)
				)
				(justify mirror)
			)
		)
		(duplicate_pad_numbers_are_jumpers no)
		(fp_rect
			(start 0.1524 0.3048)
			(end -0.1524 -0.3048)
			(stroke
				(width 0)
				(type default)
			)
			(fill no)
			(layer "B.CrtYd")
		)
		(fp_poly
			(pts
				(xy 0.2794 0.6477) (xy 0.2794 -0.6477) (xy -0.2794 -0.6477) (xy -0.2794 -0.1905) (xy -0.1524 -0.1905)
				(xy -0.1524 -0.3048) (xy 0.1524 -0.3048) (xy 0.1524 0.3048) (xy -0.1524 0.3048) (xy -0.1524 -0.1778)
				(xy -0.2794 -0.1778) (xy -0.2794 0.6477)
			)
			(stroke
				(width 0)
				(type default)
			)
			(fill no)
			(layer "B.CrtYd")
		)
		(fp_rect
			(start 0.2794 0.6477)
			(end -0.2794 -0.6477)
			(stroke
				(width 0)
				(type default)
			)
			(fill no)
			(layer "B.Fab")
		)
		(pad "1" smd custom
			(at 0 -0.2794)
			(size 0.0762 0.0762)
			(layers "B.Cu" "B.Mask" "B.Paste")
			(net "GB_VDDA")
			(options
				(clearance outline)
				(anchor circle)
			)
			(primitives
				(gr_poly
					(pts
						(arc
							(start 0.1524 0.127)
							(mid 0.137521 0.162921)
							(end 0.1016 0.1778)
						)
						(arc
							(start -0.1016 0.1778)
							(mid -0.137521 0.162921)
							(end -0.1524 0.127)
						)
						(arc
							(start -0.1524 -0.127)
							(mid -0.137521 -0.162921)
							(end -0.1016 -0.1778)
						)
						(arc
							(start 0.1016 -0.1778)
							(mid 0.137521 -0.162921)
							(end 0.1524 -0.127)
						)
					)
					(width 0)
					(fill yes)
				)
			)
		)
		(pad "2" smd custom
			(at 0 0.2794)
			(size 0.0762 0.0762)
			(layers "B.Cu" "B.Mask" "B.Paste")
			(net "GND")
			(options
				(clearance outline)
				(anchor circle)
			)
			(primitives
				(gr_poly
					(pts
						(arc
							(start 0.1524 0.127)
							(mid 0.137521 0.162921)
							(end 0.1016 0.1778)
						)
						(arc
							(start -0.1016 0.1778)
							(mid -0.137521 0.162921)
							(end -0.1524 0.127)
						)
						(arc
							(start -0.1524 -0.127)
							(mid -0.137521 -0.162921)
							(end -0.1016 -0.1778)
						)
						(arc
							(start 0.1016 -0.1778)
							(mid 0.137521 -0.162921)
							(end 0.1524 -0.127)
						)
					)
					(width 0)
					(fill yes)
				)
			)
		)
	)
	(footprint ""
		(layer "B.Cu")
		(at 70.612 -51.943 90)
		(property "Reference" "R159"
			(at 0 0 90)
			(layer "B.SilkS")
			(hide yes)
			(effects
				(font
					(size 1.27 1.27)
				)
				(justify mirror)
			)
		)
		(property "Value" "D51R3F-2-GP"
			(at 0.0254 -2.5146 90)
			(unlocked yes)
			(layer "B.Fab")
			(hide yes)
			(effects
				(font
					(size 1.016 1.016)
					(thickness 0.1524)
				)
				(justify mirror)
			)
		)
		(property "Device Type" "R603H22"
			(at 0.0254 -4.0386 90)
			(unlocked yes)
			(layer "B.Fab")
			(hide yes)
			(effects
				(font
					(size 1.016 1.016)
					(thickness 0.1524)
				)
				(justify mirror)
			)
		)
		(duplicate_pad_numbers_are_jumpers no)
		(fp_line
			(start 0.4826 0)
			(end 0.2032 0)
			(stroke
				(width 0.2032)
				(type default)
			)
			(layer "B.SilkS")
		)
		(fp_line
			(start -0.2032 0)
			(end -0.4826 0)
			(stroke
				(width 0.2032)
				(type default)
			)
			(layer "B.SilkS")
		)
		(fp_rect
			(start 0.5842 1.3335)
			(end -0.5842 -1.3335)
			(stroke
				(width 0)
				(type default)
			)
			(fill no)
			(layer "B.CrtYd")
		)
		(fp_rect
			(start 0.5842 1.3335)
			(end -0.5842 -1.3335)
			(stroke
				(width 0)
				(type default)
			)
			(fill no)
			(layer "B.Fab")
		)
		(pad "1" smd custom
			(at 0 -0.762 270)
			(size 0.2159 0.2159)
			(layers "B.Cu" "B.Mask" "B.Paste")
			(net "P0V9")
			(options
				(clearance outline)
				(anchor circle)
			)
			(primitives
				(gr_poly
					(pts
						(arc
							(start -0.3302 0.4318)
							(mid -0.402042 0.402042)
							(end -0.4318 0.3302)
						)
						(arc
							(start -0.4318 -0.3302)
							(mid -0.402042 -0.402042)
							(end -0.3302 -0.4318)
						)
						(arc
							(start 0.3302 -0.4318)
							(mid 0.402042 -0.402042)
							(end 0.4318 -0.3302)
						)
						(arc
							(start 0.4318 0.3302)
							(mid 0.402042 0.402042)
							(end 0.3302 0.4318)
						)
					)
					(width 0)
					(fill yes)
				)
			)
		)
		(pad "2" smd custom
			(at 0 0.762 270)
			(size 0.2159 0.2159)
			(layers "B.Cu" "B.Mask" "B.Paste")
			(net "GB_VDDA")
			(options
				(clearance outline)
				(anchor circle)
			)
			(primitives
				(gr_poly
					(pts
						(arc
							(start -0.3302 0.4318)
							(mid -0.402042 0.402042)
							(end -0.4318 0.3302)
						)
						(arc
							(start -0.4318 -0.3302)
							(mid -0.402042 -0.402042)
							(end -0.3302 -0.4318)
						)
						(arc
							(start 0.3302 -0.4318)
							(mid 0.402042 -0.402042)
							(end 0.4318 -0.3302)
						)
						(arc
							(start 0.4318 0.3302)
							(mid 0.402042 0.402042)
							(end 0.3302 0.4318)
						)
					)
					(width 0)
					(fill yes)
				)
			)
		)
	)
	(footprint ""
		(layer "B.Cu")
		(at 126.3777 -82.3341)
		(property "Reference" "TP161"
			(at 0 0 0)
			(layer "B.SilkS")
			(hide yes)
			(effects
				(font
					(size 1.27 1.27)
				)
				(justify mirror)
			)
		)
		(property "Value" "TPAD28-2-GP"
			(at 0.0127 -1.6637 0)
			(unlocked yes)
			(layer "B.Fab")
			(hide yes)
			(effects
				(font
					(size 1.016 1.016)
					(thickness 0.1524)
				)
				(justify mirror)
			)
		)
		(property "Device Type" "TPAD28"
			(at 0.0127 -3.1877 0)
			(unlocked yes)
			(layer "B.Fab")
			(hide yes)
			(effects
				(font
					(size 1.016 1.016)
					(thickness 0.1524)
				)
				(justify mirror)
			)
		)
		(duplicate_pad_numbers_are_jumpers no)
		(fp_poly
			(pts
				(arc
					(start 0.3556 0)
					(mid -0.3556 0)
					(end 0.3556 0)
				)
			)
			(stroke
				(width 0)
				(type default)
			)
			(fill no)
			(layer "B.CrtYd")
		)
		(fp_poly
			(pts
				(arc
					(start 0.6096 0)
					(mid -0.6096 0)
					(end 0.6096 0)
				)
			)
			(stroke
				(width 0)
				(type default)
			)
			(fill no)
			(layer "B.Fab")
		)
		(pad "1" smd circle
			(at 0 0 180)
			(size 0.7112 0.7112)
			(layers "B.Cu" "B.Mask" "B.Paste")
			(net "ICE_TDO")
		)
	)
	(footprint ""
		(layer "B.Cu")
		(at 133.8326 -44.3992 180)
		(property "Reference" "C27"
			(at 0 0 0)
			(layer "B.SilkS")
			(hide yes)
			(effects
				(font
					(size 1.27 1.27)
				)
				(justify mirror)
			)
		)
		(property "Value" "SCD01U16V1KX-GP"
			(at 2.8321 -1.7399 180)
			(unlocked yes)
			(layer "B.Fab")
			(hide yes)
			(effects
				(font
					(size 1.016 1.016)
					(thickness 0.1524)
				)
				(justify mirror)
			)
		)
		(property "Device Type" "C0201H13"
			(at 2.8321 -3.2639 180)
			(unlocked yes)
			(layer "B.Fab")
			(hide yes)
			(effects
				(font
					(size 1.016 1.016)
					(thickness 0.1524)
				)
				(justify mirror)
			)
		)
		(duplicate_pad_numbers_are_jumpers no)
		(fp_rect
			(start 0.2794 0.6477)
			(end -0.2794 -0.6477)
			(stroke
				(width 0)
				(type default)
			)
			(fill no)
			(layer "B.CrtYd")
		)
		(fp_rect
			(start 0.2794 0.6477)
			(end -0.2794 -0.6477)
			(stroke
				(width 0)
				(type default)
			)
			(fill no)
			(layer "B.Fab")
		)
		(pad "1" smd custom
			(at 0 -0.2794)
			(size 0.0762 0.0762)
			(layers "B.Cu" "B.Mask" "B.Paste")
			(net "PHY_DPB_TO_SCC_30_DP")
			(options
				(clearance outline)
				(anchor circle)
			)
			(primitives
				(gr_poly
					(pts
						(arc
							(start 0.1524 0.127)
							(mid 0.137521 0.162921)
							(end 0.1016 0.1778)
						)
						(arc
							(start -0.1016 0.1778)
							(mid -0.137521 0.162921)
							(end -0.1524 0.127)
						)
						(arc
							(start -0.1524 -0.127)
							(mid -0.137521 -0.162921)
							(end -0.1016 -0.1778)
						)
						(arc
							(start 0.1016 -0.1778)
							(mid 0.137521 -0.162921)
							(end 0.1524 -0.127)
						)
					)
					(width 0)
					(fill yes)
				)
			)
		)
		(pad "2" smd custom
			(at 0 0.2794)
			(size 0.0762 0.0762)
			(layers "B.Cu" "B.Mask" "B.Paste")
			(net "PHY_DPB_TO_SCC_C_30_DP")
			(options
				(clearance outline)
				(anchor circle)
			)
			(primitives
				(gr_poly
					(pts
						(arc
							(start 0.1524 0.127)
							(mid 0.137521 0.162921)
							(end 0.1016 0.1778)
						)
						(arc
							(start -0.1016 0.1778)
							(mid -0.137521 0.162921)
							(end -0.1524 0.127)
						)
						(arc
							(start -0.1524 -0.127)
							(mid -0.137521 -0.162921)
							(end -0.1016 -0.1778)
						)
						(arc
							(start 0.1016 -0.1778)
							(mid 0.137521 -0.162921)
							(end 0.1524 -0.127)
						)
					)
					(width 0)
					(fill yes)
				)
			)
		)
	)
	(footprint ""
		(layer "B.Cu")
		(at 137.239248 -115.511834 180)
		(property "Reference" "Q36"
			(at 0 0 0)
			(layer "B.SilkS")
			(hide yes)
			(effects
				(font
					(size 1.27 1.27)
				)
				(justify mirror)
			)
		)
		(property "Value" "FDS8878-G-GP"
			(at 3.707384 -1.5367 180)
			(unlocked yes)
			(layer "B.Fab")
			(hide yes)
			(effects
				(font
					(size 1.016 1.016)
					(thickness 0.1524)
				)
				(justify mirror)
			)
		)
		(property "Device Type" "SOIC8H69"
			(at 3.707384 -3.0607 180)
			(unlocked yes)
			(layer "B.Fab")
			(hide yes)
			(effects
				(font
					(size 1.016 1.016)
					(thickness 0.1524)
				)
				(justify mirror)
			)
		)
		(duplicate_pad_numbers_are_jumpers no)
		(fp_line
			(start 2.7432 1.4224)
			(end 2.6416 1.4224)
			(stroke
				(width 0.1524)
				(type default)
			)
			(layer "B.SilkS")
		)
		(fp_line
			(start 2.7432 1.4224)
			(end -2.1336 1.4224)
			(stroke
				(width 0.1524)
				(type default)
			)
			(layer "B.SilkS")
		)
		(fp_line
			(start 2.7432 -1.4224)
			(end 2.7432 1.4224)
			(stroke
				(width 0.1524)
				(type default)
			)
			(layer "B.SilkS")
		)
		(fp_line
			(start 2.7178 -0.508)
			(end 2.1844 -0.0508)
			(stroke
				(width 0.1524)
				(type default)
			)
			(layer "B.SilkS")
		)
		(fp_line
			(start 2.6289 3.4417)
			(end 2.6289 1.4732)
			(stroke
				(width 0.381)
				(type default)
			)
			(layer "B.SilkS")
		)
		(fp_line
			(start 2.1844 -0.0508)
			(end 2.7178 0.508)
			(stroke
				(width 0.1524)
				(type default)
			)
			(layer "B.SilkS")
		)
		(fp_line
			(start -2.1336 1.4224)
			(end -2.1336 -1.4224)
			(stroke
				(width 0.1524)
				(type default)
			)
			(layer "B.SilkS")
		)
		(fp_line
			(start -2.1336 -1.4224)
			(end 2.7432 -1.4224)
			(stroke
				(width 0.1524)
				(type default)
			)
			(layer "B.SilkS")
		)
		(fp_poly
			(pts
				(xy 2.2098 -1.4224) (xy 2.2098 1.4224) (xy -2.2098 1.4224) (xy -2.2098 -1.4224)
			)
			(stroke
				(width 0)
				(type default)
			)
			(fill yes)
			(layer "B.SilkS")
		)
		(fp_rect
			(start 2.450084 2.999994)
			(end -2.450084 -2.999994)
			(stroke
				(width 0)
				(type default)
			)
			(fill no)
			(layer "B.CrtYd")
		)
		(fp_poly
			(pts
				(xy 2.8194 3.6322) (xy 2.8194 -3.6322) (xy -2.8194 -3.6322) (xy -2.8194 1.18364) (xy -2.450084 1.18364)
				(xy -2.450084 -2.999994) (xy 2.450084 -2.999994) (xy 2.450084 2.999994) (xy -2.450084 2.999994)
				(xy -2.450084 1.18618) (xy -2.8194 1.18618) (xy -2.8194 3.6322)
			)
			(stroke
				(width 0)
				(type default)
			)
			(fill no)
			(layer "B.CrtYd")
		)
		(fp_rect
			(start 2.8194 3.6322)
			(end -2.8194 -3.6322)
			(stroke
				(width 0)
				(type default)
			)
			(fill no)
			(layer "B.Fab")
		)
		(pad "1" smd rect
			(at 1.905 2.54)
			(size 0.635 1.651)
			(layers "B.Cu" "B.Mask" "B.Paste")
			(net "P1V5_C")
		)
		(pad "2" smd rect
			(at 0.635 2.54)
			(size 0.635 1.651)
			(layers "B.Cu" "B.Mask" "B.Paste")
			(net "P1V5_C")
		)
		(pad "3" smd rect
			(at -0.635 2.54)
			(size 0.635 1.651)
			(layers "B.Cu" "B.Mask" "B.Paste")
			(net "P1V5_C")
		)
		(pad "4" smd rect
			(at -1.905 2.54)
			(size 0.635 1.651)
			(layers "B.Cu" "B.Mask" "B.Paste")
			(net "P1V5_C_PG_G")
		)
		(pad "5" smd rect
			(at -1.905 -2.54)
			(size 0.635 1.651)
			(layers "B.Cu" "B.Mask" "B.Paste")
			(net "P1V5_E_OUT")
		)
		(pad "6" smd rect
			(at -0.635 -2.54)
			(size 0.635 1.651)
			(layers "B.Cu" "B.Mask" "B.Paste")
			(net "P1V5_E_OUT")
		)
		(pad "7" smd rect
			(at 0.635 -2.54)
			(size 0.635 1.651)
			(layers "B.Cu" "B.Mask" "B.Paste")
			(net "P1V5_E_OUT")
		)
		(pad "8" smd rect
			(at 1.905 -2.54)
			(size 0.635 1.651)
			(layers "B.Cu" "B.Mask" "B.Paste")
			(net "P1V5_E_OUT")
		)
	)
	(footprint ""
		(layer "B.Cu")
		(at 179.9082 -28.7782 90)
		(property "Reference" "TP55"
			(at 0 0 90)
			(layer "B.SilkS")
			(hide yes)
			(effects
				(font
					(size 1.27 1.27)
				)
				(justify mirror)
			)
		)
		(property "Value" "TPAD28-2-GP"
			(at 0.0127 -1.6637 90)
			(unlocked yes)
			(layer "B.Fab")
			(hide yes)
			(effects
				(font
					(size 1.016 1.016)
					(thickness 0.1524)
				)
				(justify mirror)
			)
		)
		(property "Device Type" "TPAD28"
			(at 0.0127 -3.1877 90)
			(unlocked yes)
			(layer "B.Fab")
			(hide yes)
			(effects
				(font
					(size 1.016 1.016)
					(thickness 0.1524)
				)
				(justify mirror)
			)
		)
		(duplicate_pad_numbers_are_jumpers no)
		(fp_poly
			(pts
				(arc
					(start 0 0.3556)
					(mid 0 -0.3556)
					(end 0 0.3556)
				)
			)
			(stroke
				(width 0)
				(type default)
			)
			(fill no)
			(layer "B.CrtYd")
		)
		(fp_poly
			(pts
				(arc
					(start 0 0.6096)
					(mid 0 -0.6096)
					(end 0 0.6096)
				)
			)
			(stroke
				(width 0)
				(type default)
			)
			(fill no)
			(layer "B.Fab")
		)
		(pad "1" smd circle
			(at 0 0 270)
			(size 0.7112 0.7112)
			(layers "B.Cu" "B.Mask" "B.Paste")
			(net "IOC_GPIO_2")
		)
	)
	(footprint ""
		(layer "B.Cu")
		(at 175.312578 -52.221638)
		(property "Reference" "TP134"
			(at 0 0 0)
			(layer "B.SilkS")
			(hide yes)
			(effects
				(font
					(size 1.27 1.27)
				)
				(justify mirror)
			)
		)
		(property "Value" "TPAD28-2-GP"
			(at 0.0127 -1.6637 0)
			(unlocked yes)
			(layer "B.Fab")
			(hide yes)
			(effects
				(font
					(size 1.016 1.016)
					(thickness 0.1524)
				)
				(justify mirror)
			)
		)
		(property "Device Type" "TPAD28"
			(at 0.0127 -3.1877 0)
			(unlocked yes)
			(layer "B.Fab")
			(hide yes)
			(effects
				(font
					(size 1.016 1.016)
					(thickness 0.1524)
				)
				(justify mirror)
			)
		)
		(duplicate_pad_numbers_are_jumpers no)
		(fp_poly
			(pts
				(arc
					(start 0.3556 0)
					(mid -0.3556 0)
					(end 0.3556 0)
				)
			)
			(stroke
				(width 0)
				(type default)
			)
			(fill no)
			(layer "B.CrtYd")
		)
		(fp_poly
			(pts
				(arc
					(start 0.6096 0)
					(mid -0.6096 0)
					(end 0.6096 0)
				)
			)
			(stroke
				(width 0)
				(type default)
			)
			(fill no)
			(layer "B.Fab")
		)
		(pad "1" smd circle
			(at 0 0 180)
			(size 0.7112 0.7112)
			(layers "B.Cu" "B.Mask" "B.Paste")
			(net "JTAG_IOC_TCK")
		)
	)
	(footprint ""
		(layer "B.Cu")
		(at 134.606538 -84.709)
		(property "Reference" "R63"
			(at 0 0 0)
			(layer "B.SilkS")
			(hide yes)
			(effects
				(font
					(size 1.27 1.27)
				)
				(justify mirror)
			)
		)
		(property "Value" "1KR2F-3-GP"
			(at -0.064008 -3.993896 0)
			(unlocked yes)
			(layer "B.Fab")
			(hide yes)
			(effects
				(font
					(size 1.016 1.016)
					(thickness 0.1524)
				)
				(justify mirror)
			)
		)
		(property "Device Type" "R402H16"
			(at -0.064008 -5.517896 0)
			(unlocked yes)
			(layer "B.Fab")
			(hide yes)
			(effects
				(font
					(size 1.016 1.016)
					(thickness 0.1524)
				)
				(justify mirror)
			)
		)
		(duplicate_pad_numbers_are_jumpers no)
		(fp_line
			(start -0.508 -0.9398)
			(end 0.508 -0.9398)
			(stroke
				(width 0.1524)
				(type default)
			)
			(layer "B.SilkS")
		)
		(fp_line
			(start 0.508 -0.9398)
			(end 0.508 0.9398)
			(stroke
				(width 0.1524)
				(type default)
			)
			(layer "B.SilkS")
		)
		(fp_rect
			(start 0.508 0.9398)
			(end -0.508 -0.9398)
			(stroke
				(width 0)
				(type default)
			)
			(fill no)
			(layer "B.CrtYd")
		)
		(fp_rect
			(start 0.508 0.9398)
			(end -0.508 -0.9398)
			(stroke
				(width 0)
				(type default)
			)
			(fill no)
			(layer "B.Fab")
		)
		(pad "1" smd custom
			(at 0 -0.4445 180)
			(size 0.1397 0.1397)
			(layers "B.Cu" "B.Mask" "B.Paste")
			(net "P1V8_E")
			(options
				(clearance outline)
				(anchor circle)
			)
			(primitives
				(gr_poly
					(pts
						(arc
							(start -0.1778 0.2794)
							(mid -0.249642 0.249642)
							(end -0.2794 0.1778)
						)
						(arc
							(start -0.2794 -0.1778)
							(mid -0.249642 -0.249642)
							(end -0.1778 -0.2794)
						)
						(arc
							(start 0.1778 -0.2794)
							(mid 0.249642 -0.249642)
							(end 0.2794 -0.1778)
						)
						(arc
							(start 0.2794 0.1778)
							(mid 0.249642 0.249642)
							(end 0.1778 0.2794)
						)
					)
					(width 0)
					(fill yes)
				)
			)
		)
		(pad "2" smd custom
			(at 0 0.4445 180)
			(size 0.1397 0.1397)
			(layers "B.Cu" "B.Mask" "B.Paste")
			(net "I2C_EXP_IOC_SDA8")
			(options
				(clearance outline)
				(anchor circle)
			)
			(primitives
				(gr_poly
					(pts
						(arc
							(start -0.1778 0.2794)
							(mid -0.249642 0.249642)
							(end -0.2794 0.1778)
						)
						(arc
							(start -0.2794 -0.1778)
							(mid -0.249642 -0.249642)
							(end -0.1778 -0.2794)
						)
						(arc
							(start 0.1778 -0.2794)
							(mid 0.249642 -0.249642)
							(end 0.2794 -0.1778)
						)
						(arc
							(start 0.2794 0.1778)
							(mid 0.249642 0.249642)
							(end 0.1778 0.2794)
						)
					)
					(width 0)
					(fill yes)
				)
			)
		)
	)
)
